(kicad_pcb
	(version 20260206)
	(generator "pcbnew")
	(generator_version "10.0")
	(general
		(thickness 1.6)
		(legacy_teardrops no)
	)
	(paper "A4")
	(title_block
		(title "Bryce Canyon_SCC_16316-1_OCP.brd")
		(comment 1 "Bryce Canyon / footprints 398-405 of 1561")
	)
	(layers
		(0 "F.Cu" signal "TOP")
		(4 "In1.Cu" signal "L2GND")
		(6 "In2.Cu" signal "L3")
		(8 "In3.Cu" signal "L4VCC")
		(10 "In4.Cu" signal "L5VCC")
		(12 "In5.Cu" signal "L6")
		(14 "In6.Cu" signal "L7GND")
		(2 "B.Cu" signal "BOTTOM")
		(9 "F.Adhes" user "F.Adhesive")
		(11 "B.Adhes" user "B.Adhesive")
		(13 "F.Paste" user "Package Geometry/Pastemask Top")
		(15 "B.Paste" user "Package Geometry/Pastemask Bottom")
		(5 "F.SilkS" user "Ref Des/Silkscreen Top")
		(7 "B.SilkS" user "Ref Des/Silkscreen Bottom")
		(1 "F.Mask" user "Board Geometry/Soldermask Top")
		(3 "B.Mask" user "Board Geometry/Soldermask Bottom")
		(17 "Dwgs.User" user "User.Drawings")
		(19 "Cmts.User" user "User.Comments")
		(21 "Eco1.User" user "User.Eco1")
		(23 "Eco2.User" user "User.Eco2")
		(25 "Edge.Cuts" user "Board Geometry/Outline")
		(27 "Margin" user)
		(31 "F.CrtYd" user "Package Geometry/Place Bound Top")
		(29 "B.CrtYd" user "Package Geometry/Place Bound Bottom")
		(35 "F.Fab" user "Ref Des/Assembly Top")
		(33 "B.Fab" user "Ref Des/Assembly Bottom")
	)
	(footprint ""
		(layer "F.Cu")
		(at 71.612252 -78.140306 180)
		(property "Reference" "U122"
			(at 0 0 180)
			(layer "F.SilkS")
			(hide yes)
			(effects
				(font
					(size 1.27 1.27)
				)
			)
		)
		(property "Value" "NX3L1G66GW-GP"
			(at -2.3368 -8.6868 180)
			(unlocked yes)
			(layer "F.Fab")
			(hide yes)
			(effects
				(font
					(size 1.016 1.016)
					(thickness 0.1524)
				)
			)
		)
		(property "Device Type" "SC70-5H44"
			(at -2.3114 -10.414 180)
			(unlocked yes)
			(layer "F.Fab")
			(hide yes)
			(effects
				(font
					(size 1.016 1.016)
					(thickness 0.1524)
				)
			)
		)
		(duplicate_pad_numbers_are_jumpers no)
		(fp_line
			(start 1.3843 -1.8034)
			(end 1.3843 -1.1176)
			(stroke
				(width 0.3302)
				(type default)
			)
			(layer "F.SilkS")
		)
		(fp_line
			(start 1.27 1.7018)
			(end -1.27 1.7018)
			(stroke
				(width 0.1524)
				(type default)
			)
			(layer "F.SilkS")
		)
		(fp_line
			(start 1.27 -1.7018)
			(end 1.27 1.7018)
			(stroke
				(width 0.1524)
				(type default)
			)
			(layer "F.SilkS")
		)
		(fp_line
			(start 0.6604 -1.8034)
			(end 1.3843 -1.8034)
			(stroke
				(width 0.3302)
				(type default)
			)
			(layer "F.SilkS")
		)
		(fp_line
			(start -1.27 1.7018)
			(end -1.27 -1.7018)
			(stroke
				(width 0.1524)
				(type default)
			)
			(layer "F.SilkS")
		)
		(fp_line
			(start -1.27 -1.7018)
			(end 1.27 -1.7018)
			(stroke
				(width 0.1524)
				(type default)
			)
			(layer "F.SilkS")
		)
		(fp_rect
			(start -1.524 1.9558)
			(end 1.524 -1.9558)
			(stroke
				(width 0)
				(type default)
			)
			(fill no)
			(layer "F.CrtYd")
		)
		(fp_poly
			(pts
				(xy -1.524 -1.9558) (xy 1.524 -1.9558) (xy 1.524 1.9558) (xy -1.524 1.9558)
			)
			(stroke
				(width 0)
				(type default)
			)
			(fill no)
			(layer "F.Fab")
		)
		(pad "1" smd rect
			(at 0.65024 -0.8255 180)
			(size 0.4064 1.2192)
			(layers "F.Cu" "F.Mask" "F.Paste")
			(net "I2C_EXP_IOC_SDA8")
		)
		(pad "2" smd rect
			(at 0 -0.8255 180)
			(size 0.4064 1.2192)
			(layers "F.Cu" "F.Mask" "F.Paste")
			(net "I2C_IOC_4_R_SDA")
		)
		(pad "3" smd rect
			(at -0.65024 -0.8255 180)
			(size 0.4064 1.2192)
			(layers "F.Cu" "F.Mask" "F.Paste")
			(net "GND")
		)
		(pad "4" smd rect
			(at -0.65024 0.8255 180)
			(size 0.4064 1.2192)
			(layers "F.Cu" "F.Mask" "F.Paste")
			(net "PCIE_COMP_TO_SCC_RST_R_0")
		)
		(pad "5" smd rect
			(at 0.65024 0.8255 180)
			(size 0.4064 1.2192)
			(layers "F.Cu" "F.Mask" "F.Paste")
			(net "U122_VCC")
		)
	)
	(footprint ""
		(layer "F.Cu")
		(at 70.485 -37.465 90)
		(property "Reference" "L11"
			(at 0 0 90)
			(layer "F.SilkS")
			(hide yes)
			(effects
				(font
					(size 1.27 1.27)
				)
			)
		)
		(property "Value" "MPZ2012S300AT-GP"
			(at 0 -4.2418 90)
			(unlocked yes)
			(layer "F.Fab")
			(hide yes)
			(effects
				(font
					(size 1.016 1.016)
					(thickness 0.1524)
				)
			)
		)
		(property "Device Type" "L805H42"
			(at 0 -5.7912 90)
			(unlocked yes)
			(layer "F.Fab")
			(hide yes)
			(effects
				(font
					(size 1.016 1.016)
					(thickness 0.1524)
				)
			)
		)
		(duplicate_pad_numbers_are_jumpers no)
		(fp_line
			(start 0.889 -1.7018)
			(end 0.889 1.7018)
			(stroke
				(width 0.1524)
				(type default)
			)
			(layer "F.SilkS")
		)
		(fp_line
			(start -0.889 -1.7018)
			(end 0.889 -1.7018)
			(stroke
				(width 0.1524)
				(type default)
			)
			(layer "F.SilkS")
		)
		(fp_line
			(start 0.889 1.7018)
			(end -0.889 1.7018)
			(stroke
				(width 0.1524)
				(type default)
			)
			(layer "F.SilkS")
		)
		(fp_line
			(start -0.889 1.7018)
			(end -0.889 -1.7018)
			(stroke
				(width 0.1524)
				(type default)
			)
			(layer "F.SilkS")
		)
		(fp_rect
			(start -0.9652 1.778)
			(end 0.9652 -1.778)
			(stroke
				(width 0)
				(type default)
			)
			(fill no)
			(layer "F.CrtYd")
		)
		(fp_rect
			(start -0.9652 1.778)
			(end 0.9652 -1.778)
			(stroke
				(width 0)
				(type default)
			)
			(fill no)
			(layer "F.Fab")
		)
		(pad "1" smd rect
			(at 0 -0.9652 90)
			(size 1.397 1.143)
			(layers "F.Cu" "F.Mask" "F.Paste")
			(net "P0V9")
		)
		(pad "2" smd rect
			(at 0 0.9652 90)
			(size 1.397 1.143)
			(layers "F.Cu" "F.Mask" "F.Paste")
			(net "GB_VDDA")
		)
	)
	(footprint ""
		(layer "F.Cu")
		(at 146.249898 -47.0408 102)
		(property "Reference" "C339"
			(at 0 0 102)
			(layer "F.SilkS")
			(hide yes)
			(effects
				(font
					(size 1.27 1.27)
				)
			)
		)
		(property "Value" "SCD01U16V1KX-GP"
			(at -2.832048 -1.739777 102)
			(unlocked yes)
			(layer "F.Fab")
			(hide yes)
			(effects
				(font
					(size 1.016 1.016)
					(thickness 0.1524)
				)
			)
		)
		(property "Device Type" "C0201H13"
			(at -2.831925 -3.263781 102)
			(unlocked yes)
			(layer "F.Fab")
			(hide yes)
			(effects
				(font
					(size 1.016 1.016)
					(thickness 0.1524)
				)
			)
		)
		(duplicate_pad_numbers_are_jumpers no)
		(fp_poly
			(pts
				(xy -0.279454 -0.647706) (xy 0.279346 -0.647706) (xy 0.279346 0.647694) (xy -0.279454 0.647694)
			)
			(stroke
				(width 0)
				(type default)
			)
			(fill no)
			(layer "F.CrtYd")
		)
		(fp_poly
			(pts
				(xy -0.279454 -0.647706) (xy 0.279346 -0.647706) (xy 0.279346 0.647694) (xy -0.279454 0.647694)
			)
			(stroke
				(width 0)
				(type default)
			)
			(fill no)
			(layer "F.Fab")
		)
		(pad "1" smd custom
			(at -0.000001 -0.2794 102)
			(size 0.0762 0.0762)
			(layers "F.Cu" "F.Mask" "F.Paste")
			(net "PHY_SCC_TO_IOC_45_DP")
			(options
				(clearance outline)
				(anchor circle)
			)
			(primitives
				(gr_poly
					(pts
						(arc
							(start 0.1524 -0.127)
							(mid 0.137521 -0.162921)
							(end 0.1016 -0.1778)
						)
						(arc
							(start -0.1016 -0.1778)
							(mid -0.137521 -0.162921)
							(end -0.1524 -0.127)
						)
						(arc
							(start -0.1524 0.127)
							(mid -0.137521 0.162921)
							(end -0.1016 0.1778)
						)
						(arc
							(start 0.1016 0.1778)
							(mid 0.137521 0.162921)
							(end 0.1524 0.127)
						)
					)
					(width 0)
					(fill yes)
				)
			)
		)
		(pad "2" smd custom
			(at 0.000001 0.2794 102)
			(size 0.0762 0.0762)
			(layers "F.Cu" "F.Mask" "F.Paste")
			(net "PHY_SCC_TO_IOC_C_45_DP")
			(options
				(clearance outline)
				(anchor circle)
			)
			(primitives
				(gr_poly
					(pts
						(arc
							(start 0.1524 -0.127)
							(mid 0.137521 -0.162921)
							(end 0.1016 -0.1778)
						)
						(arc
							(start -0.1016 -0.1778)
							(mid -0.137521 -0.162921)
							(end -0.1524 -0.127)
						)
						(arc
							(start -0.1524 0.127)
							(mid -0.137521 0.162921)
							(end -0.1016 0.1778)
						)
						(arc
							(start 0.1016 0.1778)
							(mid 0.137521 0.162921)
							(end 0.1524 0.127)
						)
					)
					(width 0)
					(fill yes)
				)
			)
		)
	)
	(footprint ""
		(layer "F.Cu")
		(at 174.314866 -23.556976 90)
		(property "Reference" "VIA5"
			(at 0 0 90)
			(layer "F.SilkS")
			(hide yes)
			(effects
				(font
					(size 1.27 1.27)
				)
			)
		)
		(property "Value" "85OHM-8L-1D6MM-L16L18-GP"
			(at 4.064 0.6096 90)
			(unlocked yes)
			(layer "F.Fab")
			(hide yes)
			(effects
				(font
					(size 1.016 1.016)
					(thickness 0.1524)
				)
			)
		)
		(property "Device Type" "VIA-PCIE-4P-368076"
			(at 4.064 -0.9144 90)
			(unlocked yes)
			(layer "F.Fab")
			(hide yes)
			(effects
				(font
					(size 1.016 1.016)
					(thickness 0.1524)
				)
			)
		)
		(duplicate_pad_numbers_are_jumpers no)
		(fp_rect
			(start -1.8415 0.381)
			(end 1.8415 -0.381)
			(stroke
				(width 0)
				(type default)
			)
			(fill no)
			(layer "F.CrtYd")
		)
		(fp_rect
			(start -1.8415 0.381)
			(end 1.8415 -0.381)
			(stroke
				(width 0)
				(type default)
			)
			(fill no)
			(layer "F.Fab")
		)
		(pad "1" thru_hole circle
			(at -1.4605 0 90)
			(size 0.508 0.508)
			(drill 0.254)
			(layers "*.Cu" "*.Mask")
			(remove_unused_layers no)
			(net "GND")
			(clearance 0.127)
			(thermal_gap 0.127)
		)
		(pad "2" thru_hole circle
			(at -0.4445 0 90)
			(size 0.508 0.508)
			(drill 0.254)
			(layers "*.Cu" "*.Mask")
			(remove_unused_layers no)
			(net "PCIE_COMP_TO_SCC_4_DP")
			(clearance 0.127)
			(thermal_gap 0.127)
		)
		(pad "3" thru_hole circle
			(at 0.4445 0 90)
			(size 0.508 0.508)
			(drill 0.254)
			(layers "*.Cu" "*.Mask")
			(remove_unused_layers no)
			(net "PCIE_COMP_TO_SCC_4_DN")
			(clearance 0.127)
			(thermal_gap 0.127)
		)
		(pad "4" thru_hole circle
			(at 1.4605 0 90)
			(size 0.508 0.508)
			(drill 0.254)
			(layers "*.Cu" "*.Mask")
			(remove_unused_layers no)
			(net "GND")
			(clearance 0.127)
			(thermal_gap 0.127)
		)
	)
	(footprint ""
		(layer "F.Cu")
		(at 165.273736 -56.29402)
		(property "Reference" "TP125"
			(at 0 0 0)
			(layer "F.SilkS")
			(hide yes)
			(effects
				(font
					(size 1.27 1.27)
				)
			)
		)
		(property "Value" "TPAD28-2-GP"
			(at -0.0127 -1.6637 0)
			(unlocked yes)
			(layer "F.Fab")
			(hide yes)
			(effects
				(font
					(size 1.016 1.016)
					(thickness 0.1524)
				)
			)
		)
		(property "Device Type" "TPAD28"
			(at -0.0127 -3.1877 0)
			(unlocked yes)
			(layer "F.Fab")
			(hide yes)
			(effects
				(font
					(size 1.016 1.016)
					(thickness 0.1524)
				)
			)
		)
		(duplicate_pad_numbers_are_jumpers no)
		(fp_poly
			(pts
				(arc
					(start 0.3556 0)
					(mid -0.3556 0)
					(end 0.3556 0)
				)
			)
			(stroke
				(width 0)
				(type default)
			)
			(fill no)
			(layer "F.CrtYd")
		)
		(fp_poly
			(pts
				(arc
					(start 0.6096 0)
					(mid -0.6096 0)
					(end 0.6096 0)
				)
			)
			(stroke
				(width 0)
				(type default)
			)
			(fill no)
			(layer "F.Fab")
		)
		(pad "1" smd circle
			(at 0 0)
			(size 0.7112 0.7112)
			(layers "F.Cu" "F.Mask" "F.Paste")
			(net "ICE1_TMS")
		)
	)
	(footprint ""
		(layer "F.Cu")
		(at 62.61862 -17.408144)
		(property "Reference" "R576"
			(at 0 0 0)
			(layer "F.SilkS")
			(hide yes)
			(effects
				(font
					(size 1.27 1.27)
				)
			)
		)
		(property "Value" "0R2J-2-GP"
			(at 0.064008 -3.993896 0)
			(unlocked yes)
			(layer "F.Fab")
			(hide yes)
			(effects
				(font
					(size 1.016 1.016)
					(thickness 0.1524)
				)
			)
		)
		(property "Device Type" "R402H16"
			(at 0.064008 -5.517896 0)
			(unlocked yes)
			(layer "F.Fab")
			(hide yes)
			(effects
				(font
					(size 1.016 1.016)
					(thickness 0.1524)
				)
			)
		)
		(duplicate_pad_numbers_are_jumpers no)
		(fp_line
			(start -0.508 -0.9398)
			(end -0.508 0.9398)
			(stroke
				(width 0.1524)
				(type default)
			)
			(layer "F.SilkS")
		)
		(fp_line
			(start 0.508 -0.9398)
			(end -0.508 -0.9398)
			(stroke
				(width 0.1524)
				(type default)
			)
			(layer "F.SilkS")
		)
		(fp_rect
			(start -0.508 0.9398)
			(end 0.508 -0.9398)
			(stroke
				(width 0)
				(type default)
			)
			(fill no)
			(layer "F.CrtYd")
		)
		(fp_rect
			(start -0.508 0.9398)
			(end 0.508 -0.9398)
			(stroke
				(width 0)
				(type default)
			)
			(fill no)
			(layer "F.Fab")
		)
		(pad "1" smd custom
			(at 0 -0.4445)
			(size 0.1397 0.1397)
			(layers "F.Cu" "F.Mask" "F.Paste")
			(net "SCC_STBY_PGOOD_U49")
			(options
				(clearance outline)
				(anchor circle)
			)
			(primitives
				(gr_poly
					(pts
						(arc
							(start -0.1778 -0.2794)
							(mid -0.249642 -0.249642)
							(end -0.2794 -0.1778)
						)
						(arc
							(start -0.2794 0.1778)
							(mid -0.249642 0.249642)
							(end -0.1778 0.2794)
						)
						(arc
							(start 0.1778 0.2794)
							(mid 0.249642 0.249642)
							(end 0.2794 0.1778)
						)
						(arc
							(start 0.2794 -0.1778)
							(mid 0.249642 -0.249642)
							(end 0.1778 -0.2794)
						)
					)
					(width 0)
					(fill yes)
				)
			)
		)
		(pad "2" smd custom
			(at 0 0.4445)
			(size 0.1397 0.1397)
			(layers "F.Cu" "F.Mask" "F.Paste")
			(net "SCC_STBY_PGOOD")
			(options
				(clearance outline)
				(anchor circle)
			)
			(primitives
				(gr_poly
					(pts
						(arc
							(start -0.1778 -0.2794)
							(mid -0.249642 -0.249642)
							(end -0.2794 -0.1778)
						)
						(arc
							(start -0.2794 0.1778)
							(mid -0.249642 0.249642)
							(end -0.1778 0.2794)
						)
						(arc
							(start 0.1778 0.2794)
							(mid 0.249642 0.249642)
							(end 0.2794 0.1778)
						)
						(arc
							(start 0.2794 -0.1778)
							(mid 0.249642 -0.249642)
							(end 0.1778 -0.2794)
						)
					)
					(width 0)
					(fill yes)
				)
			)
		)
	)
	(footprint ""
		(layer "F.Cu")
		(at 177.5206 -122.7836 90)
		(property "Reference" "R84"
			(at 0 0 90)
			(layer "F.SilkS")
			(hide yes)
			(effects
				(font
					(size 1.27 1.27)
				)
			)
		)
		(property "Value" "0R5J-5-GP"
			(at 0 -8.9535 90)
			(unlocked yes)
			(layer "F.Fab")
			(hide yes)
			(effects
				(font
					(size 1.27 1.016)
					(thickness 0.1524)
				)
			)
		)
		(property "Device Type" "R805H24"
			(at 0 -10.6299 90)
			(unlocked yes)
			(layer "F.Fab")
			(hide yes)
			(effects
				(font
					(size 1.27 1.016)
					(thickness 0.1524)
				)
			)
		)
		(duplicate_pad_numbers_are_jumpers no)
		(fp_line
			(start 0.889 -1.7018)
			(end -0.889 -1.7018)
			(stroke
				(width 0.1524)
				(type default)
			)
			(layer "F.SilkS")
		)
		(fp_line
			(start 0.889 -1.7018)
			(end 0.889 -0.381)
			(stroke
				(width 0.1524)
				(type default)
			)
			(layer "F.SilkS")
		)
		(fp_line
			(start -0.889 -1.7018)
			(end -0.889 0.2794)
			(stroke
				(width 0.1524)
				(type default)
			)
			(layer "F.SilkS")
		)
		(fp_line
			(start -0.889 0.0762)
			(end -0.889 1.7018)
			(stroke
				(width 0.1524)
				(type default)
			)
			(layer "F.SilkS")
		)
		(fp_line
			(start 0.889 1.7018)
			(end 0.889 -0.508)
			(stroke
				(width 0.1524)
				(type default)
			)
			(layer "F.SilkS")
		)
		(fp_line
			(start -0.889 1.7018)
			(end 0.889 1.7018)
			(stroke
				(width 0.1524)
				(type default)
			)
			(layer "F.SilkS")
		)
		(fp_poly
			(pts
				(xy 0.9652 -1.778) (xy 0.9652 1.778) (xy -0.9652 1.778) (xy -0.9652 -1.778)
			)
			(stroke
				(width 0)
				(type default)
			)
			(fill no)
			(layer "F.CrtYd")
		)
		(fp_rect
			(start -0.9652 1.778)
			(end 0.9652 -1.778)
			(stroke
				(width 0)
				(type default)
			)
			(fill no)
			(layer "F.Fab")
		)
		(pad "1" smd rect
			(at 0 -0.9652 90)
			(size 1.397 1.143)
			(layers "F.Cu" "F.Mask" "F.Paste")
			(net "P1V8_E")
		)
		(pad "2" smd rect
			(at 0 0.9652 90)
			(size 1.397 1.143)
			(layers "F.Cu" "F.Mask" "F.Paste")
			(net "P1V8_E_OUT")
		)
	)
	(footprint ""
		(layer "F.Cu")
		(at 148.315172 -54.99735 102)
		(property "Reference" "C343"
			(at 0 0 102)
			(layer "F.SilkS")
			(hide yes)
			(effects
				(font
					(size 1.27 1.27)
				)
			)
		)
		(property "Value" "SCD01U16V1KX-GP"
			(at -2.832048 -1.739777 102)
			(unlocked yes)
			(layer "F.Fab")
			(hide yes)
			(effects
				(font
					(size 1.016 1.016)
					(thickness 0.1524)
				)
			)
		)
		(property "Device Type" "C0201H13"
			(at -2.831925 -3.263781 102)
			(unlocked yes)
			(layer "F.Fab")
			(hide yes)
			(effects
				(font
					(size 1.016 1.016)
					(thickness 0.1524)
				)
			)
		)
		(duplicate_pad_numbers_are_jumpers no)
		(fp_poly
			(pts
				(xy -0.279454 -0.647706) (xy 0.279346 -0.647706) (xy 0.279346 0.647694) (xy -0.279454 0.647694)
			)
			(stroke
				(width 0)
				(type default)
			)
			(fill no)
			(layer "F.CrtYd")
		)
		(fp_poly
			(pts
				(xy -0.279454 -0.647706) (xy 0.279346 -0.647706) (xy 0.279346 0.647694) (xy -0.279454 0.647694)
			)
			(stroke
				(width 0)
				(type default)
			)
			(fill no)
			(layer "F.Fab")
		)
		(pad "1" smd custom
			(at -0.000001 -0.2794 102)
			(size 0.0762 0.0762)
			(layers "F.Cu" "F.Mask" "F.Paste")
			(net "PHY_SCC_TO_IOC_47_DP")
			(options
				(clearance outline)
				(anchor circle)
			)
			(primitives
				(gr_poly
					(pts
						(arc
							(start 0.1524 -0.127)
							(mid 0.137521 -0.162921)
							(end 0.1016 -0.1778)
						)
						(arc
							(start -0.1016 -0.1778)
							(mid -0.137521 -0.162921)
							(end -0.1524 -0.127)
						)
						(arc
							(start -0.1524 0.127)
							(mid -0.137521 0.162921)
							(end -0.1016 0.1778)
						)
						(arc
							(start 0.1016 0.1778)
							(mid 0.137521 0.162921)
							(end 0.1524 0.127)
						)
					)
					(width 0)
					(fill yes)
				)
			)
		)
		(pad "2" smd custom
			(at 0.000001 0.2794 102)
			(size 0.0762 0.0762)
			(layers "F.Cu" "F.Mask" "F.Paste")
			(net "PHY_SCC_TO_IOC_C_47_DP")
			(options
				(clearance outline)
				(anchor circle)
			)
			(primitives
				(gr_poly
					(pts
						(arc
							(start 0.1524 -0.127)
							(mid 0.137521 -0.162921)
							(end 0.1016 -0.1778)
						)
						(arc
							(start -0.1016 -0.1778)
							(mid -0.137521 -0.162921)
							(end -0.1524 -0.127)
						)
						(arc
							(start -0.1524 0.127)
							(mid -0.137521 0.162921)
							(end -0.1016 0.1778)
						)
						(arc
							(start 0.1016 0.1778)
							(mid 0.137521 0.162921)
							(end 0.1524 0.127)
						)
					)
					(width 0)
					(fill yes)
				)
			)
		)
	)
)
